(kicad_pcb
	(version 20260206)
	(generator "pcbnew")
	(generator_version "10.0")
	(general
		(thickness 1.6)
		(legacy_teardrops no)
	)
	(paper "A4")
	(title_block
		(title "04192023_DAF0TMB3IC0_F0TG_MB_C_brd_V02_OCP.brd")
		(comment 1 "Grand Teton / footprints 4818-4823 of 8354")
	)
	(layers
		(0 "F.Cu" signal "TOP")
		(4 "In1.Cu" signal "GND")
		(6 "In2.Cu" signal "IN1")
		(8 "In3.Cu" signal "GND1")
		(10 "In4.Cu" signal "IN2")
		(12 "In5.Cu" signal "GND2")
		(14 "In6.Cu" signal "IN3")
		(16 "In7.Cu" signal "GND3")
		(18 "In8.Cu" signal "VCC")
		(20 "In9.Cu" signal "VCC1")
		(22 "In10.Cu" signal "GND4")
		(24 "In11.Cu" signal "IN4")
		(26 "In12.Cu" signal "GND5")
		(28 "In13.Cu" signal "IN5")
		(30 "In14.Cu" signal "GND6")
		(32 "In15.Cu" signal "IN6")
		(34 "In16.Cu" signal "GND7")
		(2 "B.Cu" signal "BOTTOM")
		(9 "F.Adhes" user "F.Adhesive")
		(11 "B.Adhes" user "B.Adhesive")
		(13 "F.Paste" user "Package Geometry/Pastemask Top")
		(15 "B.Paste" user "Package Geometry/Pastemask Bottom")
		(5 "F.SilkS" user "Ref Des/Silkscreen Top")
		(7 "B.SilkS" user "Ref Des/Silkscreen Bottom")
		(1 "F.Mask" user "Board Geometry/Soldermask Top")
		(3 "B.Mask" user "Board Geometry/Soldermask Bottom")
		(17 "Dwgs.User" user "User.Drawings")
		(19 "Cmts.User" user "User.Comments")
		(21 "Eco1.User" user "User.Eco1")
		(23 "Eco2.User" user "User.Eco2")
		(25 "Edge.Cuts" user "Board Geometry/Outline")
		(27 "Margin" user)
		(31 "F.CrtYd" user "Package Geometry/Place Bound Top")
		(29 "B.CrtYd" user "Package Geometry/Place Bound Bottom")
		(35 "F.Fab" user "Ref Des/Assembly Top")
		(33 "B.Fab" user "Ref Des/Assembly Bottom")
	)
	(footprint ""
		(layer "F.Cu")
		(at 93.375734 -177.818288 -90)
		(property "Reference" "PC255_2"
			(at 0 0 270)
			(layer "F.SilkS")
			(hide yes)
			(effects
				(font
					(size 1.27 1.27)
				)
			)
		)
		(property "Value" ""
			(at 0 0 270)
			(layer "F.Fab")
			(effects
				(font
					(size 1.27 1.27)
				)
			)
		)
		(duplicate_pad_numbers_are_jumpers no)
		(fp_line
			(start -0.7874 0.4064)
			(end -0.7874 -0.4064)
			(stroke
				(width 0.1524)
				(type default)
			)
			(layer "F.SilkS")
		)
		(fp_line
			(start 0.7874 0.4064)
			(end -0.7874 0.4064)
			(stroke
				(width 0.1524)
				(type default)
			)
			(layer "F.SilkS")
		)
		(fp_line
			(start -0.7874 -0.4064)
			(end 0.7874 -0.4064)
			(stroke
				(width 0.1524)
				(type default)
			)
			(layer "F.SilkS")
		)
		(fp_line
			(start 0.7874 -0.4064)
			(end 0.7874 0.4064)
			(stroke
				(width 0.1524)
				(type default)
			)
			(layer "F.SilkS")
		)
		(fp_line
			(start -0.67945 0.3048)
			(end -0.67945 -0.305054)
			(stroke
				(width 0.1)
				(type default)
			)
			(layer "F.Fab")
		)
		(fp_line
			(start -0.12065 0.3048)
			(end -0.67945 0.3048)
			(stroke
				(width 0.1)
				(type default)
			)
			(layer "F.Fab")
		)
		(fp_line
			(start 0.120396 0.3048)
			(end 0.120396 0.2794)
			(stroke
				(width 0.1)
				(type default)
			)
			(layer "F.Fab")
		)
		(fp_line
			(start 0.67945 0.3048)
			(end 0.120396 0.3048)
			(stroke
				(width 0.1)
				(type default)
			)
			(layer "F.Fab")
		)
		(fp_line
			(start -0.12065 0.2794)
			(end -0.12065 0.3048)
			(stroke
				(width 0.1)
				(type default)
			)
			(layer "F.Fab")
		)
		(fp_line
			(start 0.120396 0.2794)
			(end -0.12065 0.2794)
			(stroke
				(width 0.1)
				(type default)
			)
			(layer "F.Fab")
		)
		(fp_line
			(start -0.12065 -0.2794)
			(end 0.12065 -0.2794)
			(stroke
				(width 0.1)
				(type default)
			)
			(layer "F.Fab")
		)
		(fp_line
			(start 0.12065 -0.2794)
			(end 0.12065 -0.3048)
			(stroke
				(width 0.1)
				(type default)
			)
			(layer "F.Fab")
		)
		(fp_line
			(start 0.12065 -0.3048)
			(end 0.67945 -0.3048)
			(stroke
				(width 0.1)
				(type default)
			)
			(layer "F.Fab")
		)
		(fp_line
			(start 0.67945 -0.3048)
			(end 0.67945 0.3048)
			(stroke
				(width 0.1)
				(type default)
			)
			(layer "F.Fab")
		)
		(fp_line
			(start -0.67945 -0.305054)
			(end -0.12065 -0.305054)
			(stroke
				(width 0.1)
				(type default)
			)
			(layer "F.Fab")
		)
		(fp_line
			(start -0.12065 -0.305054)
			(end -0.12065 -0.2794)
			(stroke
				(width 0.1)
				(type default)
			)
			(layer "F.Fab")
		)
		(pad "1" smd circle
			(at -0.40005 0 270)
			(size 0 0)
			(layers "F.Cu" "F.Mask" "F.Paste")
			(net "PVDDCR_CPU0_P1_VCCS")
		)
		(pad "2" smd circle
			(at 0.40005 0 270)
			(size 0 0)
			(layers "F.Cu" "F.Mask" "F.Paste")
			(net "GND")
		)
	)
	(footprint ""
		(layer "F.Cu")
		(at 359.190036 -392.48588 180)
		(property "Reference" "R1008"
			(at 0 0 180)
			(layer "F.SilkS")
			(hide yes)
			(effects
				(font
					(size 1.27 1.27)
				)
			)
		)
		(property "Value" ""
			(at 0 0 180)
			(layer "F.Fab")
			(effects
				(font
					(size 1.27 1.27)
				)
			)
		)
		(duplicate_pad_numbers_are_jumpers no)
		(fp_line
			(start 0.7874 0.4064)
			(end -0.7874 0.4064)
			(stroke
				(width 0.1524)
				(type default)
			)
			(layer "F.SilkS")
		)
		(fp_line
			(start 0.7874 -0.4064)
			(end 0.7874 0.4064)
			(stroke
				(width 0.1524)
				(type default)
			)
			(layer "F.SilkS")
		)
		(fp_line
			(start -0.7874 0.4064)
			(end -0.7874 -0.4064)
			(stroke
				(width 0.1524)
				(type default)
			)
			(layer "F.SilkS")
		)
		(fp_line
			(start -0.7874 -0.4064)
			(end 0.7874 -0.4064)
			(stroke
				(width 0.1524)
				(type default)
			)
			(layer "F.SilkS")
		)
		(fp_line
			(start 0.67945 0.3048)
			(end 0.120396 0.3048)
			(stroke
				(width 0.1)
				(type default)
			)
			(layer "F.Fab")
		)
		(fp_line
			(start 0.67945 -0.3048)
			(end 0.67945 0.3048)
			(stroke
				(width 0.1)
				(type default)
			)
			(layer "F.Fab")
		)
		(fp_line
			(start 0.12065 -0.2794)
			(end 0.12065 -0.3048)
			(stroke
				(width 0.1)
				(type default)
			)
			(layer "F.Fab")
		)
		(fp_line
			(start 0.12065 -0.3048)
			(end 0.67945 -0.3048)
			(stroke
				(width 0.1)
				(type default)
			)
			(layer "F.Fab")
		)
		(fp_line
			(start 0.120396 0.3048)
			(end 0.120396 0.2794)
			(stroke
				(width 0.1)
				(type default)
			)
			(layer "F.Fab")
		)
		(fp_line
			(start 0.120396 0.2794)
			(end -0.12065 0.2794)
			(stroke
				(width 0.1)
				(type default)
			)
			(layer "F.Fab")
		)
		(fp_line
			(start -0.12065 0.3048)
			(end -0.67945 0.3048)
			(stroke
				(width 0.1)
				(type default)
			)
			(layer "F.Fab")
		)
		(fp_line
			(start -0.12065 0.2794)
			(end -0.12065 0.3048)
			(stroke
				(width 0.1)
				(type default)
			)
			(layer "F.Fab")
		)
		(fp_line
			(start -0.12065 -0.2794)
			(end 0.12065 -0.2794)
			(stroke
				(width 0.1)
				(type default)
			)
			(layer "F.Fab")
		)
		(fp_line
			(start -0.12065 -0.305054)
			(end -0.12065 -0.2794)
			(stroke
				(width 0.1)
				(type default)
			)
			(layer "F.Fab")
		)
		(fp_line
			(start -0.67945 0.3048)
			(end -0.67945 -0.305054)
			(stroke
				(width 0.1)
				(type default)
			)
			(layer "F.Fab")
		)
		(fp_line
			(start -0.67945 -0.305054)
			(end -0.12065 -0.305054)
			(stroke
				(width 0.1)
				(type default)
			)
			(layer "F.Fab")
		)
		(pad "1" smd rect
			(at -0.40005 0)
			(size 0.4572 0.508)
			(layers "F.Cu" "F.Mask" "F.Paste")
			(net "P1V8_CPU0_RT_1D")
		)
		(pad "2" smd rect
			(at 0.40005 0)
			(size 0.4572 0.508)
			(layers "F.Cu" "F.Mask" "F.Paste")
			(net "P1V8_CPU0_RT1_1A_1D")
		)
	)
	(footprint ""
		(layer "F.Cu")
		(at 113.613946 -54.882034 -90)
		(property "Reference" "R6303"
			(at 0 0 270)
			(layer "F.SilkS")
			(hide yes)
			(effects
				(font
					(size 1.27 1.27)
				)
			)
		)
		(property "Value" ""
			(at 0 0 270)
			(layer "F.Fab")
			(effects
				(font
					(size 1.27 1.27)
				)
			)
		)
		(duplicate_pad_numbers_are_jumpers no)
		(fp_line
			(start -0.7874 0.4064)
			(end -0.7874 -0.4064)
			(stroke
				(width 0.1524)
				(type default)
			)
			(layer "F.SilkS")
		)
		(fp_line
			(start 0.7874 0.4064)
			(end -0.7874 0.4064)
			(stroke
				(width 0.1524)
				(type default)
			)
			(layer "F.SilkS")
		)
		(fp_line
			(start -0.7874 -0.4064)
			(end 0.7874 -0.4064)
			(stroke
				(width 0.1524)
				(type default)
			)
			(layer "F.SilkS")
		)
		(fp_line
			(start 0.7874 -0.4064)
			(end 0.7874 0.4064)
			(stroke
				(width 0.1524)
				(type default)
			)
			(layer "F.SilkS")
		)
		(fp_line
			(start -0.67945 0.3048)
			(end -0.67945 -0.305054)
			(stroke
				(width 0.1)
				(type default)
			)
			(layer "F.Fab")
		)
		(fp_line
			(start -0.12065 0.3048)
			(end -0.67945 0.3048)
			(stroke
				(width 0.1)
				(type default)
			)
			(layer "F.Fab")
		)
		(fp_line
			(start 0.120396 0.3048)
			(end 0.120396 0.2794)
			(stroke
				(width 0.1)
				(type default)
			)
			(layer "F.Fab")
		)
		(fp_line
			(start 0.67945 0.3048)
			(end 0.120396 0.3048)
			(stroke
				(width 0.1)
				(type default)
			)
			(layer "F.Fab")
		)
		(fp_line
			(start -0.12065 0.2794)
			(end -0.12065 0.3048)
			(stroke
				(width 0.1)
				(type default)
			)
			(layer "F.Fab")
		)
		(fp_line
			(start 0.120396 0.2794)
			(end -0.12065 0.2794)
			(stroke
				(width 0.1)
				(type default)
			)
			(layer "F.Fab")
		)
		(fp_line
			(start -0.12065 -0.2794)
			(end 0.12065 -0.2794)
			(stroke
				(width 0.1)
				(type default)
			)
			(layer "F.Fab")
		)
		(fp_line
			(start 0.12065 -0.2794)
			(end 0.12065 -0.3048)
			(stroke
				(width 0.1)
				(type default)
			)
			(layer "F.Fab")
		)
		(fp_line
			(start 0.12065 -0.3048)
			(end 0.67945 -0.3048)
			(stroke
				(width 0.1)
				(type default)
			)
			(layer "F.Fab")
		)
		(fp_line
			(start 0.67945 -0.3048)
			(end 0.67945 0.3048)
			(stroke
				(width 0.1)
				(type default)
			)
			(layer "F.Fab")
		)
		(fp_line
			(start -0.67945 -0.305054)
			(end -0.12065 -0.305054)
			(stroke
				(width 0.1)
				(type default)
			)
			(layer "F.Fab")
		)
		(fp_line
			(start -0.12065 -0.305054)
			(end -0.12065 -0.2794)
			(stroke
				(width 0.1)
				(type default)
			)
			(layer "F.Fab")
		)
		(pad "1" smd circle
			(at -0.40005 0 270)
			(size 0 0)
			(layers "F.Cu" "F.Mask" "F.Paste")
			(net "P3V3_AUX")
		)
		(pad "2" smd circle
			(at 0.40005 0 270)
			(size 0 0)
			(layers "F.Cu" "F.Mask" "F.Paste")
			(net "USB_HUB2_MRP_CFG_BC_EN")
		)
	)
	(footprint ""
		(layer "F.Cu")
		(at 119.761 -426.72)
		(property "Reference" "C1958"
			(at 0 0 0)
			(layer "F.SilkS")
			(hide yes)
			(effects
				(font
					(size 1.27 1.27)
				)
			)
		)
		(property "Value" ""
			(at 0 0 0)
			(layer "F.Fab")
			(effects
				(font
					(size 1.27 1.27)
				)
			)
		)
		(duplicate_pad_numbers_are_jumpers no)
		(fp_line
			(start -0.7874 -0.4064)
			(end 0.7874 -0.4064)
			(stroke
				(width 0.1524)
				(type default)
			)
			(layer "F.SilkS")
		)
		(fp_line
			(start -0.7874 0.4064)
			(end -0.7874 -0.4064)
			(stroke
				(width 0.1524)
				(type default)
			)
			(layer "F.SilkS")
		)
		(fp_line
			(start 0.7874 -0.4064)
			(end 0.7874 0.4064)
			(stroke
				(width 0.1524)
				(type default)
			)
			(layer "F.SilkS")
		)
		(fp_line
			(start 0.7874 0.4064)
			(end -0.7874 0.4064)
			(stroke
				(width 0.1524)
				(type default)
			)
			(layer "F.SilkS")
		)
		(fp_line
			(start -0.67945 -0.305054)
			(end -0.12065 -0.305054)
			(stroke
				(width 0.1)
				(type default)
			)
			(layer "F.Fab")
		)
		(fp_line
			(start -0.67945 0.3048)
			(end -0.67945 -0.305054)
			(stroke
				(width 0.1)
				(type default)
			)
			(layer "F.Fab")
		)
		(fp_line
			(start -0.12065 -0.305054)
			(end -0.12065 -0.2794)
			(stroke
				(width 0.1)
				(type default)
			)
			(layer "F.Fab")
		)
		(fp_line
			(start -0.12065 -0.2794)
			(end 0.12065 -0.2794)
			(stroke
				(width 0.1)
				(type default)
			)
			(layer "F.Fab")
		)
		(fp_line
			(start -0.12065 0.2794)
			(end -0.12065 0.3048)
			(stroke
				(width 0.1)
				(type default)
			)
			(layer "F.Fab")
		)
		(fp_line
			(start -0.12065 0.3048)
			(end -0.67945 0.3048)
			(stroke
				(width 0.1)
				(type default)
			)
			(layer "F.Fab")
		)
		(fp_line
			(start 0.120396 0.2794)
			(end -0.12065 0.2794)
			(stroke
				(width 0.1)
				(type default)
			)
			(layer "F.Fab")
		)
		(fp_line
			(start 0.120396 0.3048)
			(end 0.120396 0.2794)
			(stroke
				(width 0.1)
				(type default)
			)
			(layer "F.Fab")
		)
		(fp_line
			(start 0.12065 -0.3048)
			(end 0.67945 -0.3048)
			(stroke
				(width 0.1)
				(type default)
			)
			(layer "F.Fab")
		)
		(fp_line
			(start 0.12065 -0.2794)
			(end 0.12065 -0.3048)
			(stroke
				(width 0.1)
				(type default)
			)
			(layer "F.Fab")
		)
		(fp_line
			(start 0.67945 -0.3048)
			(end 0.67945 0.3048)
			(stroke
				(width 0.1)
				(type default)
			)
			(layer "F.Fab")
		)
		(fp_line
			(start 0.67945 0.3048)
			(end 0.120396 0.3048)
			(stroke
				(width 0.1)
				(type default)
			)
			(layer "F.Fab")
		)
		(pad "1" smd circle
			(at -0.40005 0)
			(size 0 0)
			(layers "F.Cu" "F.Mask" "F.Paste")
			(net "P3V3_AUX")
		)
		(pad "2" smd circle
			(at 0.40005 0)
			(size 0 0)
			(layers "F.Cu" "F.Mask" "F.Paste")
			(net "GND")
		)
	)
	(footprint ""
		(layer "F.Cu")
		(at 292.126162 -337.399122)
		(property "Reference" "PL18"
			(at -2.439162 -15.888208 0)
			(unlocked yes)
			(layer "F.SilkS")
			(effects
				(font
					(size 0.7874 0.5842)
					(thickness 0.1524)
				)
				(justify left)
			)
		)
		(property "Value" ""
			(at 0 0 0)
			(layer "F.Fab")
			(effects
				(font
					(size 1.27 1.27)
				)
			)
		)
		(duplicate_pad_numbers_are_jumpers no)
		(fp_line
			(start -3.750056 -5.500116)
			(end -2.393442 -5.500116)
			(stroke
				(width 0.1524)
				(type default)
			)
			(layer "F.SilkS")
		)
		(fp_line
			(start -3.750056 5.500116)
			(end -3.750056 -5.500116)
			(stroke
				(width 0.1524)
				(type default)
			)
			(layer "F.SilkS")
		)
		(fp_line
			(start -2.393442 5.500116)
			(end -3.750056 5.500116)
			(stroke
				(width 0.1524)
				(type default)
			)
			(layer "F.SilkS")
		)
		(fp_line
			(start 2.393442 5.500116)
			(end 3.750056 5.500116)
			(stroke
				(width 0.1524)
				(type default)
			)
			(layer "F.SilkS")
		)
		(fp_line
			(start 3.750056 -5.500116)
			(end 2.393442 -5.500116)
			(stroke
				(width 0.1524)
				(type default)
			)
			(layer "F.SilkS")
		)
		(fp_line
			(start 3.750056 5.500116)
			(end 3.750056 -5.500116)
			(stroke
				(width 0.1524)
				(type default)
			)
			(layer "F.SilkS")
		)
		(fp_poly
			(pts
				(xy -3.9116 -4.249928) (xy -4.3434 -4.034028) (xy -4.3434 -4.465828)
			)
			(stroke
				(width 0)
				(type default)
			)
			(fill yes)
			(layer "F.SilkS")
		)
		(fp_line
			(start -3.750056 -5.500116)
			(end -3.750056 5.500116)
			(stroke
				(width 0.1)
				(type default)
			)
			(layer "F.Fab")
		)
		(fp_line
			(start -3.750056 5.500116)
			(end 3.750056 5.500116)
			(stroke
				(width 0.1)
				(type default)
			)
			(layer "F.Fab")
		)
		(fp_line
			(start 3.750056 -5.500116)
			(end -3.750056 -5.500116)
			(stroke
				(width 0.1)
				(type default)
			)
			(layer "F.Fab")
		)
		(fp_line
			(start 3.750056 5.500116)
			(end 3.750056 -5.500116)
			(stroke
				(width 0.1)
				(type default)
			)
			(layer "F.Fab")
		)
		(fp_poly
			(pts
				(xy -4.9276 -4.757928) (xy -4.9276 -3.741928) (xy -3.9116 -4.249928)
			)
			(stroke
				(width 0)
				(type default)
			)
			(fill yes)
			(layer "F.Fab")
		)
		(pad "1" smd rect
			(at 0 -4.249928 270)
			(size 2.413 4.5212)
			(layers "F.Cu" "F.Mask" "F.Paste")
			(net "SW_PVDDIO_P0_SW2")
		)
		(pad "2" smd rect
			(at 0 -1.175004 270)
			(size 1.3716 4.5212)
			(layers "F.Cu" "F.Mask" "F.Paste")
			(net "IND_PVDDIO_P0_CPL3")
		)
		(pad "3" smd rect
			(at 0 1.175004 270)
			(size 1.3716 4.5212)
			(layers "F.Cu" "F.Mask" "F.Paste")
			(net "IND_PVDDIO_P0_CPL2")
		)
		(pad "4" smd rect
			(at 0 4.249928 270)
			(size 2.413 4.5212)
			(layers "F.Cu" "F.Mask" "F.Paste")
			(net "PVDDIO_P0")
		)
	)
	(footprint ""
		(layer "F.Cu")
		(at 188.296804 -428.069248 90)
		(property "Reference" "R3440"
			(at 0 0 90)
			(layer "F.SilkS")
			(hide yes)
			(effects
				(font
					(size 1.27 1.27)
				)
			)
		)
		(property "Value" ""
			(at 0 0 90)
			(layer "F.Fab")
			(effects
				(font
					(size 1.27 1.27)
				)
			)
		)
		(duplicate_pad_numbers_are_jumpers no)
		(fp_line
			(start 0.7874 -0.4064)
			(end 0.7874 0.4064)
			(stroke
				(width 0.1524)
				(type default)
			)
			(layer "F.SilkS")
		)
		(fp_line
			(start -0.7874 -0.4064)
			(end 0.7874 -0.4064)
			(stroke
				(width 0.1524)
				(type default)
			)
			(layer "F.SilkS")
		)
		(fp_line
			(start 0.7874 0.4064)
			(end -0.7874 0.4064)
			(stroke
				(width 0.1524)
				(type default)
			)
			(layer "F.SilkS")
		)
		(fp_line
			(start -0.7874 0.4064)
			(end -0.7874 -0.4064)
			(stroke
				(width 0.1524)
				(type default)
			)
			(layer "F.SilkS")
		)
		(fp_line
			(start -0.12065 -0.305054)
			(end -0.12065 -0.2794)
			(stroke
				(width 0.1)
				(type default)
			)
			(layer "F.Fab")
		)
		(fp_line
			(start -0.67945 -0.305054)
			(end -0.12065 -0.305054)
			(stroke
				(width 0.1)
				(type default)
			)
			(layer "F.Fab")
		)
		(fp_line
			(start 0.67945 -0.3048)
			(end 0.67945 0.3048)
			(stroke
				(width 0.1)
				(type default)
			)
			(layer "F.Fab")
		)
		(fp_line
			(start 0.12065 -0.3048)
			(end 0.67945 -0.3048)
			(stroke
				(width 0.1)
				(type default)
			)
			(layer "F.Fab")
		)
		(fp_line
			(start 0.12065 -0.2794)
			(end 0.12065 -0.3048)
			(stroke
				(width 0.1)
				(type default)
			)
			(layer "F.Fab")
		)
		(fp_line
			(start -0.12065 -0.2794)
			(end 0.12065 -0.2794)
			(stroke
				(width 0.1)
				(type default)
			)
			(layer "F.Fab")
		)
		(fp_line
			(start 0.120396 0.2794)
			(end -0.12065 0.2794)
			(stroke
				(width 0.1)
				(type default)
			)
			(layer "F.Fab")
		)
		(fp_line
			(start -0.12065 0.2794)
			(end -0.12065 0.3048)
			(stroke
				(width 0.1)
				(type default)
			)
			(layer "F.Fab")
		)
		(fp_line
			(start 0.67945 0.3048)
			(end 0.120396 0.3048)
			(stroke
				(width 0.1)
				(type default)
			)
			(layer "F.Fab")
		)
		(fp_line
			(start 0.120396 0.3048)
			(end 0.120396 0.2794)
			(stroke
				(width 0.1)
				(type default)
			)
			(layer "F.Fab")
		)
		(fp_line
			(start -0.12065 0.3048)
			(end -0.67945 0.3048)
			(stroke
				(width 0.1)
				(type default)
			)
			(layer "F.Fab")
		)
		(fp_line
			(start -0.67945 0.3048)
			(end -0.67945 -0.305054)
			(stroke
				(width 0.1)
				(type default)
			)
			(layer "F.Fab")
		)
		(pad "1" smd circle
			(at -0.40005 0 90)
			(size 0 0)
			(layers "F.Cu" "F.Mask" "F.Paste")
			(net "GPU_BASE_ID0")
		)
		(pad "2" smd circle
			(at 0.40005 0 90)
			(size 0 0)
			(layers "F.Cu" "F.Mask" "F.Paste")
			(net "GND")
		)
	)
)
